# S9S_MB_2U (Grand Teton) — schematic netlist excerpt (pin names and nets, part order shuffled) for the footprints in the layout excerpt that follows; sources: Cadence DE-HDL packaged netlist, KiCad conversion of 03242023_DA0F0TMBIJ0_F0T_Motherboard_J_brd_V01_OCP.brd

C1933  Q_CAP  0.01UF 50V 10% X7R  pkg C0402  page 217 : A = P3V3_AUX_FPGA_VCCIO1 ; B = GND
R3038  Q_RES  5.11K 1% CHIP  pkg 0402LF  page 200 : A = P3V3_AUX ; B = FM_PCH_SPARE0

(kicad_pcb
	(version 20260206)
	(generator "pcbnew")
	(generator_version "10.0")
	(general
		(thickness 1.6)
		(legacy_teardrops no)
	)
	(paper "A4")
	(title_block
		(title "03242023_DA0F0TMBIJ0_F0T_Motherboard_J_brd_V01_OCP.brd")
		(comment 1 "Grand Teton / footprints 4849-4850 of 6105")
	)
	(layers
		(0 "F.Cu" signal "TOP")
		(4 "In1.Cu" signal "GND")
		(6 "In2.Cu" signal "IN1")
		(8 "In3.Cu" signal "GND1")
		(10 "In4.Cu" signal "IN2")
		(12 "In5.Cu" signal "GND2")
		(14 "In6.Cu" signal "IN3")
		(16 "In7.Cu" signal "GND3")
		(18 "In8.Cu" signal "VCC")
		(20 "In9.Cu" signal "VCC1")
		(22 "In10.Cu" signal "GND4")
		(24 "In11.Cu" signal "IN4")
		(26 "In12.Cu" signal "GND5")
		(28 "In13.Cu" signal "IN5")
		(30 "In14.Cu" signal "GND6")
		(32 "In15.Cu" signal "IN6")
		(34 "In16.Cu" signal "GND7")
		(2 "B.Cu" signal "BOTTOM")
		(9 "F.Adhes" user "F.Adhesive")
		(11 "B.Adhes" user "B.Adhesive")
		(13 "F.Paste" user "Package Geometry/Pastemask Top")
		(15 "B.Paste" user "Package Geometry/Pastemask Bottom")
		(5 "F.SilkS" user "Ref Des/Silkscreen Top")
		(7 "B.SilkS" user "Ref Des/Silkscreen Bottom")
		(1 "F.Mask" user "Board Geometry/Soldermask Top")
		(3 "B.Mask" user "Board Geometry/Soldermask Bottom")
		(17 "Dwgs.User" user "User.Drawings")
		(19 "Cmts.User" user "User.Comments")
		(21 "Eco1.User" user "User.Eco1")
		(23 "Eco2.User" user "User.Eco2")
		(25 "Edge.Cuts" user "Board Geometry/Outline")
		(27 "Margin" user)
		(31 "F.CrtYd" user "Package Geometry/Place Bound Top")
		(29 "B.CrtYd" user "Package Geometry/Place Bound Bottom")
		(35 "F.Fab" user "Ref Des/Assembly Top")
		(33 "B.Fab" user "Ref Des/Assembly Bottom")
	)
	(footprint ""
		(layer "B.Cu")
		(at 317.90259 -30.507178 180)
		(property "Reference" "R3038"
			(at 0 0 0)
			(layer "B.SilkS")
			(hide yes)
			(effects
				(font
					(size 1.27 1.27)
				)
				(justify mirror)
			)
		)
		(property "Value" ""
			(at 0 0 0)
			(layer "B.Fab")
			(effects
				(font
					(size 1.27 1.27)
				)
				(justify mirror)
			)
		)
		(duplicate_pad_numbers_are_jumpers no)
		(fp_line
			(start 0.7874 0.4064)
			(end 0.7874 -0.4064)
			(stroke
				(width 0.1524)
				(type default)
			)
			(layer "B.SilkS")
		)
		(fp_line
			(start 0.7874 -0.4064)
			(end -0.7874 -0.4064)
			(stroke
				(width 0.1524)
				(type default)
			)
			(layer "B.SilkS")
		)
		(fp_line
			(start -0.7874 0.4064)
			(end 0.7874 0.4064)
			(stroke
				(width 0.1524)
				(type default)
			)
			(layer "B.SilkS")
		)
		(fp_line
			(start -0.7874 -0.4064)
			(end -0.7874 0.4064)
			(stroke
				(width 0.1524)
				(type default)
			)
			(layer "B.SilkS")
		)
		(fp_line
			(start 0.67945 0.3048)
			(end 0.67945 -0.305054)
			(stroke
				(width 0.1)
				(type default)
			)
			(layer "B.Fab")
		)
		(fp_line
			(start 0.67945 -0.305054)
			(end 0.12065 -0.305054)
			(stroke
				(width 0.1)
				(type default)
			)
			(layer "B.Fab")
		)
		(fp_line
			(start 0.12065 0.3048)
			(end 0.67945 0.3048)
			(stroke
				(width 0.1)
				(type default)
			)
			(layer "B.Fab")
		)
		(fp_line
			(start 0.12065 0.2794)
			(end 0.12065 0.3048)
			(stroke
				(width 0.1)
				(type default)
			)
			(layer "B.Fab")
		)
		(fp_line
			(start 0.12065 -0.2794)
			(end -0.12065 -0.2794)
			(stroke
				(width 0.1)
				(type default)
			)
			(layer "B.Fab")
		)
		(fp_line
			(start 0.12065 -0.305054)
			(end 0.12065 -0.2794)
			(stroke
				(width 0.1)
				(type default)
			)
			(layer "B.Fab")
		)
		(fp_line
			(start -0.120396 0.3048)
			(end -0.120396 0.2794)
			(stroke
				(width 0.1)
				(type default)
			)
			(layer "B.Fab")
		)
		(fp_line
			(start -0.120396 0.2794)
			(end 0.12065 0.2794)
			(stroke
				(width 0.1)
				(type default)
			)
			(layer "B.Fab")
		)
		(fp_line
			(start -0.12065 -0.2794)
			(end -0.12065 -0.3048)
			(stroke
				(width 0.1)
				(type default)
			)
			(layer "B.Fab")
		)
		(fp_line
			(start -0.12065 -0.3048)
			(end -0.67945 -0.3048)
			(stroke
				(width 0.1)
				(type default)
			)
			(layer "B.Fab")
		)
		(fp_line
			(start -0.67945 0.3048)
			(end -0.120396 0.3048)
			(stroke
				(width 0.1)
				(type default)
			)
			(layer "B.Fab")
		)
		(fp_line
			(start -0.67945 -0.3048)
			(end -0.67945 0.3048)
			(stroke
				(width 0.1)
				(type default)
			)
			(layer "B.Fab")
		)
		(pad "1" smd circle
			(at 0.40005 0)
			(size 0 0)
			(layers "B.Cu" "B.Mask" "B.Paste")
			(net "P3V3_AUX")
		)
		(pad "2" smd circle
			(at -0.40005 0)
			(size 0 0)
			(layers "B.Cu" "B.Mask" "B.Paste")
			(net "FM_PCH_SPARE0")
		)
	)
	(footprint ""
		(layer "B.Cu")
		(at 176.555654 -115.775486 90)
		(property "Reference" "C1933"
			(at 0 0 90)
			(layer "B.SilkS")
			(hide yes)
			(effects
				(font
					(size 1.27 1.27)
				)
				(justify mirror)
			)
		)
		(property "Value" ""
			(at 0 0 90)
			(layer "B.Fab")
			(effects
				(font
					(size 1.27 1.27)
				)
				(justify mirror)
			)
		)
		(duplicate_pad_numbers_are_jumpers no)
		(fp_line
			(start 0.69215 -0.2921)
			(end -0.69215 -0.2921)
			(stroke
				(width 0.1524)
				(type default)
			)
			(layer "B.SilkS")
		)
		(fp_line
			(start -0.69215 -0.2921)
			(end -0.69215 0.2921)
			(stroke
				(width 0.1524)
				(type default)
			)
			(layer "B.SilkS")
		)
		(fp_line
			(start 0.69215 0.2921)
			(end 0.69215 -0.2921)
			(stroke
				(width 0.1524)
				(type default)
			)
			(layer "B.SilkS")
		)
		(fp_line
			(start -0.69215 0.2921)
			(end 0.69215 0.2921)
			(stroke
				(width 0.1524)
				(type default)
			)
			(layer "B.SilkS")
		)
		(fp_line
			(start 0.51435 -0.2794)
			(end -0.51435 -0.2794)
			(stroke
				(width 0.1)
				(type default)
			)
			(layer "B.Fab")
		)
		(fp_line
			(start -0.51435 -0.2794)
			(end -0.51435 0.2794)
			(stroke
				(width 0.1)
				(type default)
			)
			(layer "B.Fab")
		)
		(fp_line
			(start 0.51435 0.2794)
			(end 0.51435 -0.2794)
			(stroke
				(width 0.1)
				(type default)
			)
			(layer "B.Fab")
		)
		(fp_line
			(start -0.51435 0.2794)
			(end 0.51435 0.2794)
			(stroke
				(width 0.1)
				(type default)
			)
			(layer "B.Fab")
		)
		(pad "1" smd circle
			(at 0.40005 0 270)
			(size 0 0)
			(layers "B.Cu" "B.Mask" "B.Paste")
			(net "P3V3_AUX_FPGA_VCCIO1")
		)
		(pad "2" smd circle
			(at -0.40005 0 270)
			(size 0 0)
			(layers "B.Cu" "B.Mask" "B.Paste")
			(net "GND")
		)
		(zone
			(layer "B.Cu")
			(hatch none 0.5)
			(connect_pads
				(clearance 0)
			)
			(min_thickness 0.25)
			(keepout
				(tracks not_allowed)
				(vias allowed)
				(pads allowed)
				(copperpour not_allowed)
				(footprints allowed)
			)
			(placement
				(enabled no)
				(sheetname "")
			)
			(fill
				(thermal_gap 0.5)
				(thermal_bridge_width 0.5)
				(island_removal_mode 0)
			)
			(polygon
				(pts
					(xy 176.643284 -115.965986) (xy 176.70145 -115.874546) (xy 176.70145 -115.675156) (xy 176.643284 -115.584986)
					(xy 176.468024 -115.584986) (xy 176.409604 -115.675156) (xy 176.409604 -115.874546) (xy 176.46777 -115.965986)
				)
			)
		)
	)
)
